(kicad_pcb
	(version 20260206)
	(generator "pcbnew")
	(generator_version "10.0")
	(general
		(thickness 1.6)
		(legacy_teardrops no)
	)
	(paper "A4")
	(title_block
		(title "netronome-mezz — pcbd0082-001_rev01_jul9_a.brd")
		(comment 1 "Open CloudServer (Microsoft) / footprint 225 of 714 (U1), pads 352-465 of 1022")
	)
	(layers
		(0 "F.Cu" signal "TOP")
		(4 "In1.Cu" signal "02_GND")
		(6 "In2.Cu" signal "03_SIG")
		(8 "In3.Cu" signal "04_SIG")
		(10 "In4.Cu" signal "05_GND")
		(12 "In5.Cu" signal "06_PWR1")
		(14 "In6.Cu" signal "07_SIG")
		(16 "In7.Cu" signal "08_SIG")
		(18 "In8.Cu" signal "09_GND")
		(2 "B.Cu" signal "BOTTOM")
		(9 "F.Adhes" user "F.Adhesive")
		(11 "B.Adhes" user "B.Adhesive")
		(13 "F.Paste" user "Package Geometry/Pastemask Top")
		(15 "B.Paste" user "Package Geometry/Pastemask Bottom")
		(5 "F.SilkS" user "Ref Des/Silkscreen Top")
		(7 "B.SilkS" user "Ref Des/Silkscreen Bottom")
		(1 "F.Mask" user "Board Geometry/Soldermask Top")
		(3 "B.Mask" user "Board Geometry/Soldermask Bottom")
		(17 "Dwgs.User" user "User.Drawings")
		(19 "Cmts.User" user "User.Comments")
		(21 "Eco1.User" user "User.Eco1")
		(23 "Eco2.User" user "User.Eco2")
		(25 "Edge.Cuts" user "Board Geometry/Outline")
		(27 "Margin" user)
		(31 "F.CrtYd" user "Package Geometry/Place Bound Top")
		(29 "B.CrtYd" user "Package Geometry/Place Bound Bottom")
		(35 "F.Fab" user "Ref Des/Assembly Top")
		(33 "B.Fab" user "Ref Des/Assembly Bottom")
		(45 "User.4" user "COMPVAL_TYPE_BOTTOM")
	)
	(footprint ""
		(layer "F.Cu")
		(at 54.737 18.542 180)
		(property "Reference" "U1"
			(at -12.192 17.9705 0)
			(unlocked yes)
			(layer "F.SilkS")
			(effects
				(font
					(size 1.27 0.9652)
					(thickness 0.1524)
				)
				(justify left)
			)
		)
		(property "Value" "*"
			(at -0.4826 1.74879 180)
			(unlocked yes)
			(layer "F.Fab")
			(hide yes)
			(effects
				(font
					(size 1.27 0.9652)
					(thickness 0.000001)
				)
				(justify left)
			)
		)
		(property "Device Type" "ICBG0048"
			(at -0.4826 1.74879 180)
			(unlocked yes)
			(layer "F.Fab")
			(hide yes)
			(effects
				(font
					(size 1.27 0.9652)
					(thickness 0.000001)
				)
				(justify left)
			)
		)
		(duplicate_pad_numbers_are_jumpers no)
		(pad "AK32" smd circle
			(at 15.499994 13.499998 180)
			(size 0.6604 0.6604)
			(layers "F.Cu" "F.Mask" "F.Paste")
			(net "GND")
		)
		(pad "AL1" smd circle
			(at -15.499994 14.499996 180)
			(size 0.6604 0.6604)
			(layers "F.Cu" "F.Mask" "F.Paste")
			(net "GND")
		)
		(pad "AL2" smd circle
			(at -14.499996 14.499996 180)
			(size 0.6604 0.6604)
			(layers "F.Cu" "F.Mask" "F.Paste")
			(net "GND")
		)
		(pad "AL3" smd circle
			(at -13.499998 14.499996 180)
			(size 0.508 0.508)
			(layers "F.Cu" "F.Mask" "F.Paste")
			(net "GND")
		)
		(pad "AL4" smd circle
			(at -12.5 14.499996 180)
			(size 0.508 0.508)
			(layers "F.Cu" "F.Mask" "F.Paste")
			(net "_NC_NFP_PCIE1_PET0_P")
		)
		(pad "AL5" smd circle
			(at -11.500002 14.499996 180)
			(size 0.508 0.508)
			(layers "F.Cu" "F.Mask" "F.Paste")
			(net "_NC_NFP_PCIE1_PET1_N")
		)
		(pad "AL6" smd circle
			(at -10.500004 14.499996 180)
			(size 0.508 0.508)
			(layers "F.Cu" "F.Mask" "F.Paste")
			(net "_NC_NFP_PCIE1_PET2_P")
		)
		(pad "AL7" smd circle
			(at -9.500006 14.499996 180)
			(size 0.508 0.508)
			(layers "F.Cu" "F.Mask" "F.Paste")
			(net "_NC_NFP_PCIE1_PET3_N")
		)
		(pad "AL8" smd circle
			(at -8.500008 14.499996 180)
			(size 0.508 0.508)
			(layers "F.Cu" "F.Mask" "F.Paste")
			(net "_NC_NFP_PCIE1_PET4_P")
		)
		(pad "AL9" smd circle
			(at -7.50001 14.499996 180)
			(size 0.508 0.508)
			(layers "F.Cu" "F.Mask" "F.Paste")
			(net "_NC_NFP_PCIE1_PET5_N")
		)
		(pad "AL10" smd circle
			(at -6.500012 14.499996 180)
			(size 0.508 0.508)
			(layers "F.Cu" "F.Mask" "F.Paste")
			(net "_NC_NFP_PCIE1_PET6_P")
		)
		(pad "AL11" smd circle
			(at -5.499989 14.499996 180)
			(size 0.508 0.508)
			(layers "F.Cu" "F.Mask" "F.Paste")
			(net "_NC_NFP_PCIE1_PET7_N")
		)
		(pad "AL12" smd circle
			(at -4.499991 14.499996 180)
			(size 0.508 0.508)
			(layers "F.Cu" "F.Mask" "F.Paste")
			(net "_NFP_PCIE0_PER0_P")
		)
		(pad "AL13" smd circle
			(at -3.499993 14.499996 180)
			(size 0.508 0.508)
			(layers "F.Cu" "F.Mask" "F.Paste")
			(net "_NFP_PCIE0_PER1_N")
		)
		(pad "AL14" smd circle
			(at -2.499995 14.499996 180)
			(size 0.508 0.508)
			(layers "F.Cu" "F.Mask" "F.Paste")
			(net "_NFP_PCIE0_PER2_P")
		)
		(pad "AL15" smd circle
			(at -1.499997 14.499996 180)
			(size 0.508 0.508)
			(layers "F.Cu" "F.Mask" "F.Paste")
			(net "_NFP_PCIE0_PER3_N")
		)
		(pad "AL16" smd circle
			(at -0.499999 14.499996 180)
			(size 0.508 0.508)
			(layers "F.Cu" "F.Mask" "F.Paste")
			(net "_NFP_PCIE0_PER4_P")
		)
		(pad "AL17" smd circle
			(at 0.499999 14.499996 180)
			(size 0.508 0.508)
			(layers "F.Cu" "F.Mask" "F.Paste")
			(net "_NFP_PCIE0_PER5_N")
		)
		(pad "AL18" smd circle
			(at 1.499997 14.499996 180)
			(size 0.508 0.508)
			(layers "F.Cu" "F.Mask" "F.Paste")
			(net "_NFP_PCIE0_PER6_P")
		)
		(pad "AL19" smd circle
			(at 2.499995 14.499996 180)
			(size 0.508 0.508)
			(layers "F.Cu" "F.Mask" "F.Paste")
			(net "_NFP_PCIE0_PER7_N")
		)
		(pad "AL20" smd circle
			(at 3.499993 14.499996 180)
			(size 0.508 0.508)
			(layers "F.Cu" "F.Mask" "F.Paste")
			(net "NFP_SERDES0_TX0_P")
		)
		(pad "AL21" smd circle
			(at 4.499991 14.499996 180)
			(size 0.508 0.508)
			(layers "F.Cu" "F.Mask" "F.Paste")
			(net "_NC_NFP_SERDES0_TX1_N")
		)
		(pad "AL22" smd circle
			(at 5.499989 14.499996 180)
			(size 0.508 0.508)
			(layers "F.Cu" "F.Mask" "F.Paste")
			(net "_NC_NFP_SERDES0_TX2_P")
		)
		(pad "AL23" smd circle
			(at 6.500012 14.499996 180)
			(size 0.508 0.508)
			(layers "F.Cu" "F.Mask" "F.Paste")
			(net "_NC_NFP_SERDES0_TX3_N")
		)
		(pad "AL24" smd circle
			(at 7.50001 14.499996 180)
			(size 0.508 0.508)
			(layers "F.Cu" "F.Mask" "F.Paste")
			(net "NFP_SERDES1_TX0_P")
		)
		(pad "AL25" smd circle
			(at 8.500008 14.499996 180)
			(size 0.508 0.508)
			(layers "F.Cu" "F.Mask" "F.Paste")
			(net "NFP_SERDES1_TX1_N")
		)
		(pad "AL26" smd circle
			(at 9.500006 14.499996 180)
			(size 0.508 0.508)
			(layers "F.Cu" "F.Mask" "F.Paste")
			(net "NFP_SERDES1_TX2_P")
		)
		(pad "AL27" smd circle
			(at 10.500004 14.499996 180)
			(size 0.508 0.508)
			(layers "F.Cu" "F.Mask" "F.Paste")
			(net "NFP_SERDES1_TX3_N")
		)
		(pad "AL28" smd circle
			(at 11.500002 14.499996 180)
			(size 0.508 0.508)
			(layers "F.Cu" "F.Mask" "F.Paste")
			(net "_NC_NFP_SERDES2_TX0_P")
		)
		(pad "AL29" smd circle
			(at 12.5 14.499996 180)
			(size 0.508 0.508)
			(layers "F.Cu" "F.Mask" "F.Paste")
			(net "_NC_NFP_SERDES2_TX1_N")
		)
		(pad "AL30" smd circle
			(at 13.499998 14.499996 180)
			(size 0.508 0.508)
			(layers "F.Cu" "F.Mask" "F.Paste")
			(net "GND")
		)
		(pad "AL31" smd circle
			(at 14.499996 14.499996 180)
			(size 0.6604 0.6604)
			(layers "F.Cu" "F.Mask" "F.Paste")
			(net "GND")
		)
		(pad "AL32" smd circle
			(at 15.499994 14.499996 180)
			(size 0.6604 0.6604)
			(layers "F.Cu" "F.Mask" "F.Paste")
			(net "GND")
		)
		(pad "AM2" smd circle
			(at -14.499996 15.499994 180)
			(size 0.6604 0.6604)
			(layers "F.Cu" "F.Mask" "F.Paste")
			(net "GND")
		)
		(pad "AM3" smd circle
			(at -13.499998 15.499994 180)
			(size 0.6604 0.6604)
			(layers "F.Cu" "F.Mask" "F.Paste")
			(net "GND")
		)
		(pad "AM4" smd circle
			(at -12.5 15.499994 180)
			(size 0.508 0.508)
			(layers "F.Cu" "F.Mask" "F.Paste")
			(net "GND")
		)
		(pad "AM5" smd circle
			(at -11.500002 15.499994 180)
			(size 0.508 0.508)
			(layers "F.Cu" "F.Mask" "F.Paste")
			(net "_NC_NFP_PCIE1_PET1_P")
		)
		(pad "AM6" smd circle
			(at -10.500004 15.499994 180)
			(size 0.508 0.508)
			(layers "F.Cu" "F.Mask" "F.Paste")
			(net "GND")
		)
		(pad "AM7" smd circle
			(at -9.500006 15.499994 180)
			(size 0.508 0.508)
			(layers "F.Cu" "F.Mask" "F.Paste")
			(net "_NC_NFP_PCIE1_PET3_P")
		)
		(pad "AM8" smd circle
			(at -8.500008 15.499994 180)
			(size 0.508 0.508)
			(layers "F.Cu" "F.Mask" "F.Paste")
			(net "GND")
		)
		(pad "AM9" smd circle
			(at -7.50001 15.499994 180)
			(size 0.508 0.508)
			(layers "F.Cu" "F.Mask" "F.Paste")
			(net "_NC_NFP_PCIE1_PET5_P")
		)
		(pad "AM10" smd circle
			(at -6.500012 15.499994 180)
			(size 0.508 0.508)
			(layers "F.Cu" "F.Mask" "F.Paste")
			(net "GND")
		)
		(pad "AM11" smd circle
			(at -5.499989 15.499994 180)
			(size 0.508 0.508)
			(layers "F.Cu" "F.Mask" "F.Paste")
			(net "_NC_NFP_PCIE1_PET7_P")
		)
		(pad "AM12" smd circle
			(at -4.499991 15.499994 180)
			(size 0.508 0.508)
			(layers "F.Cu" "F.Mask" "F.Paste")
			(net "GND")
		)
		(pad "AM13" smd circle
			(at -3.499993 15.499994 180)
			(size 0.508 0.508)
			(layers "F.Cu" "F.Mask" "F.Paste")
			(net "_NFP_PCIE0_PER1_P")
		)
		(pad "AM14" smd circle
			(at -2.499995 15.499994 180)
			(size 0.508 0.508)
			(layers "F.Cu" "F.Mask" "F.Paste")
			(net "GND")
		)
		(pad "AM15" smd circle
			(at -1.499997 15.499994 180)
			(size 0.508 0.508)
			(layers "F.Cu" "F.Mask" "F.Paste")
			(net "_NFP_PCIE0_PER3_P")
		)
		(pad "AM16" smd circle
			(at -0.499999 15.499994 180)
			(size 0.508 0.508)
			(layers "F.Cu" "F.Mask" "F.Paste")
			(net "GND")
		)
		(pad "AM17" smd circle
			(at 0.499999 15.499994 180)
			(size 0.508 0.508)
			(layers "F.Cu" "F.Mask" "F.Paste")
			(net "_NFP_PCIE0_PER5_P")
		)
		(pad "AM18" smd circle
			(at 1.499997 15.499994 180)
			(size 0.508 0.508)
			(layers "F.Cu" "F.Mask" "F.Paste")
			(net "GND")
		)
		(pad "AM19" smd circle
			(at 2.499995 15.499994 180)
			(size 0.508 0.508)
			(layers "F.Cu" "F.Mask" "F.Paste")
			(net "_NFP_PCIE0_PER7_P")
		)
		(pad "AM20" smd circle
			(at 3.499993 15.499994 180)
			(size 0.508 0.508)
			(layers "F.Cu" "F.Mask" "F.Paste")
			(net "GND")
		)
		(pad "AM21" smd circle
			(at 4.499991 15.499994 180)
			(size 0.508 0.508)
			(layers "F.Cu" "F.Mask" "F.Paste")
			(net "_NC_NFP_SERDES0_TX1_P")
		)
		(pad "AM22" smd circle
			(at 5.499989 15.499994 180)
			(size 0.508 0.508)
			(layers "F.Cu" "F.Mask" "F.Paste")
			(net "GND")
		)
		(pad "AM23" smd circle
			(at 6.500012 15.499994 180)
			(size 0.508 0.508)
			(layers "F.Cu" "F.Mask" "F.Paste")
			(net "_NC_NFP_SERDES0_TX3_P")
		)
		(pad "AM24" smd circle
			(at 7.50001 15.499994 180)
			(size 0.508 0.508)
			(layers "F.Cu" "F.Mask" "F.Paste")
			(net "GND")
		)
		(pad "AM25" smd circle
			(at 8.500008 15.499994 180)
			(size 0.508 0.508)
			(layers "F.Cu" "F.Mask" "F.Paste")
			(net "NFP_SERDES1_TX1_P")
		)
		(pad "AM26" smd circle
			(at 9.500006 15.499994 180)
			(size 0.508 0.508)
			(layers "F.Cu" "F.Mask" "F.Paste")
			(net "GND")
		)
		(pad "AM27" smd circle
			(at 10.500004 15.499994 180)
			(size 0.508 0.508)
			(layers "F.Cu" "F.Mask" "F.Paste")
			(net "NFP_SERDES1_TX3_P")
		)
		(pad "AM28" smd circle
			(at 11.500002 15.499994 180)
			(size 0.508 0.508)
			(layers "F.Cu" "F.Mask" "F.Paste")
			(net "GND")
		)
		(pad "AM29" smd circle
			(at 12.5 15.499994 180)
			(size 0.508 0.508)
			(layers "F.Cu" "F.Mask" "F.Paste")
			(net "_NC_NFP_SERDES2_TX1_P")
		)
		(pad "AM30" smd circle
			(at 13.499998 15.499994 180)
			(size 0.6604 0.6604)
			(layers "F.Cu" "F.Mask" "F.Paste")
			(net "GND")
		)
		(pad "AM31" smd circle
			(at 14.499996 15.499994 180)
			(size 0.6604 0.6604)
			(layers "F.Cu" "F.Mask" "F.Paste")
			(net "GND")
		)
		(pad "B1" smd circle
			(at -15.499994 -14.499996 180)
			(size 0.6604 0.6604)
			(layers "F.Cu" "F.Mask" "F.Paste")
			(net "GND")
		)
		(pad "B2" smd circle
			(at -14.499996 -14.499996 180)
			(size 0.6604 0.6604)
			(layers "F.Cu" "F.Mask" "F.Paste")
			(net "DDR_VDDQ")
		)
		(pad "B3" smd circle
			(at -13.499998 -14.499996 180)
			(size 0.508 0.508)
			(layers "F.Cu" "F.Mask" "F.Paste")
			(net "GND")
		)
		(pad "B4" smd circle
			(at -12.5 -14.499996 180)
			(size 0.508 0.508)
			(layers "F.Cu" "F.Mask" "F.Paste")
			(net "DDR_VDDQ")
		)
		(pad "B5" smd circle
			(at -11.500002 -14.499996 180)
			(size 0.508 0.508)
			(layers "F.Cu" "F.Mask" "F.Paste")
			(net "GND")
		)
		(pad "B6" smd circle
			(at -10.500004 -14.499996 180)
			(size 0.508 0.508)
			(layers "F.Cu" "F.Mask" "F.Paste")
			(net "DDR_VDDQ")
		)
		(pad "B7" smd circle
			(at -9.500006 -14.499996 180)
			(size 0.508 0.508)
			(layers "F.Cu" "F.Mask" "F.Paste")
			(net "GND")
		)
		(pad "B8" smd circle
			(at -8.500008 -14.499996 180)
			(size 0.508 0.508)
			(layers "F.Cu" "F.Mask" "F.Paste")
			(net "DDR_VDDQ")
		)
		(pad "B9" smd circle
			(at -7.50001 -14.499996 180)
			(size 0.508 0.508)
			(layers "F.Cu" "F.Mask" "F.Paste")
			(net "GND")
		)
		(pad "B10" smd circle
			(at -6.500012 -14.499996 180)
			(size 0.508 0.508)
			(layers "F.Cu" "F.Mask" "F.Paste")
			(net "GND")
		)
		(pad "B11" smd circle
			(at -5.499989 -14.499996 180)
			(size 0.508 0.508)
			(layers "F.Cu" "F.Mask" "F.Paste")
			(net "GND")
		)
		(pad "B12" smd circle
			(at -4.499991 -14.499996 180)
			(size 0.508 0.508)
			(layers "F.Cu" "F.Mask" "F.Paste")
			(net "VDD_CORE")
		)
		(pad "B13" smd circle
			(at -3.499993 -14.499996 180)
			(size 0.508 0.508)
			(layers "F.Cu" "F.Mask" "F.Paste")
			(net "GND")
		)
		(pad "B14" smd circle
			(at -2.499995 -14.499996 180)
			(size 0.508 0.508)
			(layers "F.Cu" "F.Mask" "F.Paste")
			(net "VDD_CORE")
		)
		(pad "B15" smd circle
			(at -1.499997 -14.499996 180)
			(size 0.508 0.508)
			(layers "F.Cu" "F.Mask" "F.Paste")
			(net "GND")
		)
		(pad "B16" smd circle
			(at -0.499999 -14.499996 180)
			(size 0.508 0.508)
			(layers "F.Cu" "F.Mask" "F.Paste")
			(net "VDD_CORE")
		)
		(pad "B17" smd circle
			(at 0.499999 -14.499996 180)
			(size 0.508 0.508)
			(layers "F.Cu" "F.Mask" "F.Paste")
			(net "GND")
		)
		(pad "B18" smd circle
			(at 1.499997 -14.499996 180)
			(size 0.508 0.508)
			(layers "F.Cu" "F.Mask" "F.Paste")
			(net "VDD_CORE")
		)
		(pad "B19" smd circle
			(at 2.499995 -14.499996 180)
			(size 0.508 0.508)
			(layers "F.Cu" "F.Mask" "F.Paste")
			(net "GND")
		)
		(pad "B20" smd circle
			(at 3.499993 -14.499996 180)
			(size 0.508 0.508)
			(layers "F.Cu" "F.Mask" "F.Paste")
			(net "VDD_CORE")
		)
		(pad "B21" smd circle
			(at 4.499991 -14.499996 180)
			(size 0.508 0.508)
			(layers "F.Cu" "F.Mask" "F.Paste")
			(net "GND")
		)
		(pad "B22" smd circle
			(at 5.499989 -14.499996 180)
			(size 0.508 0.508)
			(layers "F.Cu" "F.Mask" "F.Paste")
			(net "VDD_CORE")
		)
		(pad "B23" smd circle
			(at 6.500012 -14.499996 180)
			(size 0.508 0.508)
			(layers "F.Cu" "F.Mask" "F.Paste")
			(net "GND")
		)
		(pad "B24" smd circle
			(at 7.50001 -14.499996 180)
			(size 0.508 0.508)
			(layers "F.Cu" "F.Mask" "F.Paste")
			(net "VDD_CORE")
		)
		(pad "B25" smd circle
			(at 8.500008 -14.499996 180)
			(size 0.508 0.508)
			(layers "F.Cu" "F.Mask" "F.Paste")
			(net "GND")
		)
		(pad "B26" smd circle
			(at 9.500006 -14.499996 180)
			(size 0.508 0.508)
			(layers "F.Cu" "F.Mask" "F.Paste")
			(net "VDD_CORE")
		)
		(pad "B27" smd circle
			(at 10.500004 -14.499996 180)
			(size 0.508 0.508)
			(layers "F.Cu" "F.Mask" "F.Paste")
			(net "_NC_TEST_SCAN_0_OUT35")
		)
		(pad "B28" smd circle
			(at 11.500002 -14.499996 180)
			(size 0.508 0.508)
			(layers "F.Cu" "F.Mask" "F.Paste")
			(net "_NC_TEST_SCAN_0_OUT34")
		)
		(pad "B29" smd circle
			(at 12.5 -14.499996 180)
			(size 0.508 0.508)
			(layers "F.Cu" "F.Mask" "F.Paste")
			(net "_NC_TEST_SCAN_0_OUT28")
		)
		(pad "B30" smd circle
			(at 13.499998 -14.499996 180)
			(size 0.508 0.508)
			(layers "F.Cu" "F.Mask" "F.Paste")
			(net "_NC_VDDQ_TEST_SCAN_0_OUT")
		)
		(pad "B31" smd circle
			(at 14.499996 -14.499996 180)
			(size 0.6604 0.6604)
			(layers "F.Cu" "F.Mask" "F.Paste")
			(net "GND")
		)
		(pad "B32" smd circle
			(at 15.499994 -14.499996 180)
			(size 0.6604 0.6604)
			(layers "F.Cu" "F.Mask" "F.Paste")
			(net "GND")
		)
		(pad "C1" smd circle
			(at -15.499994 -13.499998 180)
			(size 0.6604 0.6604)
			(layers "F.Cu" "F.Mask" "F.Paste")
			(net "GND")
		)
		(pad "C2" smd circle
			(at -14.499996 -13.499998 180)
			(size 0.508 0.508)
			(layers "F.Cu" "F.Mask" "F.Paste")
			(net "_NC_DDR0_32B_DQS4_P")
		)
		(pad "C3" smd circle
			(at -13.499998 -13.499998 180)
			(size 0.508 0.508)
			(layers "F.Cu" "F.Mask" "F.Paste")
			(net "_NC_DDR0_32B_DQS4_N")
		)
		(pad "C4" smd circle
			(at -12.5 -13.499998 180)
			(size 0.508 0.508)
			(layers "F.Cu" "F.Mask" "F.Paste")
			(net "_NC_DDR0_32B_CB7")
		)
		(pad "C5" smd circle
			(at -11.500002 -13.499998 180)
			(size 0.508 0.508)
			(layers "F.Cu" "F.Mask" "F.Paste")
			(net "_NC_DDR0_32B_CB0")
		)
		(pad "C6" smd circle
			(at -10.500004 -13.499998 180)
			(size 0.508 0.508)
			(layers "F.Cu" "F.Mask" "F.Paste")
			(net "_NC_NFP_DDR0_32B_PLL_DTO0")
		)
		(pad "C7" smd circle
			(at -9.500006 -13.499998 180)
			(size 0.508 0.508)
			(layers "F.Cu" "F.Mask" "F.Paste")
			(net "_NC_NFP_DDR0_32B_PLL_DTO1")
		)
		(pad "C8" smd circle
			(at -8.500008 -13.499998 180)
			(size 0.508 0.508)
			(layers "F.Cu" "F.Mask" "F.Paste")
			(net "_NC_DDR0_32B_BA1")
		)
		(pad "C9" smd circle
			(at -7.50001 -13.499998 180)
			(size 0.508 0.508)
			(layers "F.Cu" "F.Mask" "F.Paste")
			(net "DDR_VDDQ")
		)
		(pad "C10" smd circle
			(at -6.500012 -13.499998 180)
			(size 0.508 0.508)
			(layers "F.Cu" "F.Mask" "F.Paste")
			(net "GND")
		)
		(pad "C11" smd circle
			(at -5.499989 -13.499998 180)
			(size 0.508 0.508)
			(layers "F.Cu" "F.Mask" "F.Paste")
			(net "VDD_CORE")
		)
		(pad "C12" smd circle
			(at -4.499991 -13.499998 180)
			(size 0.508 0.508)
			(layers "F.Cu" "F.Mask" "F.Paste")
			(net "GND")
		)
		(pad "C13" smd circle
			(at -3.499993 -13.499998 180)
			(size 0.508 0.508)
			(layers "F.Cu" "F.Mask" "F.Paste")
			(net "VDD_CORE")
		)
		(pad "C14" smd circle
			(at -2.499995 -13.499998 180)
			(size 0.508 0.508)
			(layers "F.Cu" "F.Mask" "F.Paste")
			(net "GND")
		)
		(pad "C15" smd circle
			(at -1.499997 -13.499998 180)
			(size 0.508 0.508)
			(layers "F.Cu" "F.Mask" "F.Paste")
			(net "VDD_CORE")
		)
		(pad "C16" smd circle
			(at -0.499999 -13.499998 180)
			(size 0.508 0.508)
			(layers "F.Cu" "F.Mask" "F.Paste")
			(net "GND")
		)
		(pad "C17" smd circle
			(at 0.499999 -13.499998 180)
			(size 0.508 0.508)
			(layers "F.Cu" "F.Mask" "F.Paste")
			(net "VDD_CORE")
		)
		(pad "C18" smd circle
			(at 1.499997 -13.499998 180)
			(size 0.508 0.508)
			(layers "F.Cu" "F.Mask" "F.Paste")
			(net "GND")
		)
		(pad "C19" smd circle
			(at 2.499995 -13.499998 180)
			(size 0.508 0.508)
			(layers "F.Cu" "F.Mask" "F.Paste")
			(net "VDD_CORE")
		)
	)
)
